FILE_TYPE = MACRO_DRAWING;
SET COLOR_WIRE YELLOW;
SET COLOR_PROP ORANGE;
SET COLOR_DOT WHITE;
SET COLOR_ARC YELLOW;
SET COLOR_BODY GREEN;
SET COLOR_NOTE PURPLE;
SET PROP_DISPLAY VALUE;
SET PAGE_NUMBER P69;
FORCEADD SOCKET4677_AZIF0045P001C01CS..30
(1300 2075);
FORCEPROP 1 LAST PART_NUMBER DGA^7000023
J 0
(250 3675);
DISPLAY 0.723404 (250 3675);
PAINT GREEN (250 3675);
DISPLAY INVISIBLE (250 3675);
FORCEPROP 2 LAST PART_TYPE SMLF
J 0
(250 3850);
DISPLAY 1.021277 (250 3850);
FORCEPROP 2 LAST VALUE SOCKET4677_AZIF0045-P001C01CS
J 0
(250 3800);
DISPLAY 1.021277 (250 3800);
FORCEPROP 1 LAST MATERIAL IO
J 0
(250 3600);
DISPLAY 0.723404 (250 3600);
PAINT GREEN (250 3600);
FORCEPROP 1 LAST $LOCATION U1
J 0
(250 3750);
DISPLAY 0.723404 (250 3750);
PAINT GREEN (250 3750);
FORCEPROP 0 LASTPIN (2500 1950) $PN AA11
J 0
(2510 1960);
DISPLAY 0.680851 (2510 1960);
PAINT MONO (2510 1960);
FORCEPROP 0 LASTPIN (2500 2000) $PN AA15
J 0
(2510 2010);
DISPLAY 0.680851 (2510 2010);
PAINT MONO (2510 2010);
FORCEPROP 0 LASTPIN (2500 1900) $PN AA7
J 0
(2510 1910);
DISPLAY 0.680851 (2510 1910);
PAINT MONO (2510 1910);
FORCEPROP 0 LASTPIN (2500 2050) $PN AD85
J 0
(2510 2060);
DISPLAY 0.680851 (2510 2060);
PAINT MONO (2510 2060);
FORCEPROP 0 LASTPIN (2500 2100) $PN AD89
J 0
(2510 2110);
DISPLAY 0.680851 (2510 2110);
PAINT MONO (2510 2110);
FORCEPROP 0 LASTPIN (2500 2200) $PN AE11
J 0
(2510 2210);
DISPLAY 0.680851 (2510 2210);
PAINT MONO (2510 2210);
FORCEPROP 0 LASTPIN (2500 2250) $PN AE15
J 0
(2510 2260);
DISPLAY 0.680851 (2510 2260);
PAINT MONO (2510 2260);
FORCEPROP 0 LASTPIN (2500 2150) $PN AE7
J 0
(2510 2160);
DISPLAY 0.680851 (2510 2160);
PAINT MONO (2510 2160);
FORCEPROP 0 LASTPIN (2500 2300) $PN AF77
J 0
(2510 2310);
DISPLAY 0.680851 (2510 2310);
PAINT MONO (2510 2310);
FORCEPROP 0 LASTPIN (2500 2350) $PN AG78
J 0
(2510 2360);
DISPLAY 0.680851 (2510 2360);
PAINT MONO (2510 2360);
FORCEPROP 0 LASTPIN (2500 2400) $PN AH85
J 0
(2510 2410);
DISPLAY 0.680851 (2510 2410);
PAINT MONO (2510 2410);
FORCEPROP 0 LASTPIN (2500 2450) $PN AH89
J 0
(2510 2460);
DISPLAY 0.680851 (2510 2460);
PAINT MONO (2510 2460);
FORCEPROP 0 LASTPIN (2500 2550) $PN AJ11
J 0
(2510 2560);
DISPLAY 0.680851 (2510 2560);
PAINT MONO (2510 2560);
FORCEPROP 0 LASTPIN (2500 2600) $PN AJ15
J 0
(2510 2610);
DISPLAY 0.680851 (2510 2610);
PAINT MONO (2510 2610);
FORCEPROP 0 LASTPIN (2500 2500) $PN AJ7
J 0
(2510 2510);
DISPLAY 0.680851 (2510 2510);
PAINT MONO (2510 2510);
FORCEPROP 0 LASTPIN (2500 2650) $PN AM79
J 0
(2510 2660);
DISPLAY 0.680851 (2510 2660);
PAINT MONO (2510 2660);
FORCEPROP 0 LASTPIN (2500 2700) $PN AM85
J 0
(2510 2710);
DISPLAY 0.680851 (2510 2710);
PAINT MONO (2510 2710);
FORCEPROP 0 LASTPIN (2500 2750) $PN AM89
J 0
(2510 2760);
DISPLAY 0.680851 (2510 2760);
PAINT MONO (2510 2760);
FORCEPROP 0 LASTPIN (2500 2850) $PN AN11
J 0
(2510 2860);
DISPLAY 0.680851 (2510 2860);
PAINT MONO (2510 2860);
FORCEPROP 0 LASTPIN (2500 2900) $PN AN15
J 0
(2510 2910);
DISPLAY 0.680851 (2510 2910);
PAINT MONO (2510 2910);
FORCEPROP 0 LASTPIN (2500 2800) $PN AN7
J 0
(2510 2810);
DISPLAY 0.680851 (2510 2810);
PAINT MONO (2510 2810);
FORCEPROP 0 LASTPIN (2500 2950) $PN AN80
J 0
(2510 2960);
DISPLAY 0.680851 (2510 2960);
PAINT MONO (2510 2960);
FORCEPROP 0 LASTPIN (2500 3000) $PN AT73
J 0
(2510 3010);
DISPLAY 0.680851 (2510 3010);
PAINT MONO (2510 3010);
FORCEPROP 0 LASTPIN (2500 3050) $PN AT89
J 0
(2510 3060);
DISPLAY 0.680851 (2510 3060);
PAINT MONO (2510 3060);
FORCEPROP 0 LASTPIN (2500 3100) $PN AU15
J 0
(2510 3110);
DISPLAY 0.680851 (2510 3110);
PAINT MONO (2510 3110);
FORCEPROP 0 LASTPIN (2500 3150) $PN AW76
J 0
(2510 3160);
DISPLAY 0.680851 (2510 3160);
PAINT MONO (2510 3160);
FORCEPROP 0 LASTPIN (2500 3200) $PN AY89
J 0
(2510 3210);
DISPLAY 0.680851 (2510 3210);
PAINT MONO (2510 3210);
FORCEPROP 0 LASTPIN (2500 3250) $PN BE72
J 0
(2510 3260);
DISPLAY 0.680851 (2510 3260);
PAINT MONO (2510 3260);
FORCEPROP 0 LASTPIN (2500 3300) $PN BF77
J 0
(2510 3310);
DISPLAY 0.680851 (2510 3310);
PAINT MONO (2510 3310);
FORCEPROP 0 LASTPIN (2500 3350) $PN BH79
J 0
(2510 3360);
DISPLAY 0.680851 (2510 3360);
PAINT MONO (2510 3360);
FORCEPROP 0 LASTPIN (2500 3400) $PN BJ72
J 0
(2510 3410);
DISPLAY 0.680851 (2510 3410);
PAINT MONO (2510 3410);
FORCEPROP 0 LASTPIN (100 900) $PN BJ78
J 2
(90 910);
DISPLAY 0.680851 (90 910);
PAINT MONO (90 910);
FORCEPROP 0 LASTPIN (2500 750) $PN C84
J 0
(2510 760);
DISPLAY 0.680851 (2510 760);
PAINT MONO (2510 760);
FORCEPROP 0 LASTPIN (2500 800) $PN C88
J 0
(2510 810);
DISPLAY 0.680851 (2510 810);
PAINT MONO (2510 810);
FORCEPROP 0 LASTPIN (100 950) $PN CE74
J 2
(90 960);
DISPLAY 0.680851 (90 960);
PAINT MONO (90 960);
FORCEPROP 0 LASTPIN (100 1000) $PN CK73
J 2
(90 1010);
DISPLAY 0.680851 (90 1010);
PAINT MONO (90 1010);
FORCEPROP 0 LASTPIN (100 1050) $PN CK79
J 2
(90 1060);
DISPLAY 0.680851 (90 1060);
PAINT MONO (90 1060);
FORCEPROP 0 LASTPIN (100 1100) $PN CM73
J 2
(90 1110);
DISPLAY 0.680851 (90 1110);
PAINT MONO (90 1110);
FORCEPROP 0 LASTPIN (100 1150) $PN CN78
J 2
(90 1160);
DISPLAY 0.680851 (90 1160);
PAINT MONO (90 1160);
FORCEPROP 0 LASTPIN (100 1200) $PN CP73
J 2
(90 1210);
DISPLAY 0.680851 (90 1210);
PAINT MONO (90 1210);
FORCEPROP 0 LASTPIN (100 1250) $PN CT77
J 2
(90 1260);
DISPLAY 0.680851 (90 1260);
PAINT MONO (90 1260);
FORCEPROP 0 LASTPIN (100 1300) $PN CT85
J 2
(90 1310);
DISPLAY 0.680851 (90 1310);
PAINT MONO (90 1310);
FORCEPROP 0 LASTPIN (100 1350) $PN CY75
J 2
(90 1360);
DISPLAY 0.680851 (90 1360);
PAINT MONO (90 1360);
FORCEPROP 0 LASTPIN (100 1400) $PN CY79
J 2
(90 1410);
DISPLAY 0.680851 (90 1410);
PAINT MONO (90 1410);
FORCEPROP 0 LASTPIN (100 1450) $PN CY85
J 2
(90 1460);
DISPLAY 0.680851 (90 1460);
PAINT MONO (90 1460);
FORCEPROP 0 LASTPIN (100 1500) $PN CY89
J 2
(90 1510);
DISPLAY 0.680851 (90 1510);
PAINT MONO (90 1510);
FORCEPROP 0 LASTPIN (100 1550) $PN DD77
J 2
(90 1560);
DISPLAY 0.680851 (90 1560);
PAINT MONO (90 1560);
FORCEPROP 0 LASTPIN (100 1600) $PN DD83
J 2
(90 1610);
DISPLAY 0.680851 (90 1610);
PAINT MONO (90 1610);
FORCEPROP 0 LASTPIN (100 1650) $PN DD85
J 2
(90 1660);
DISPLAY 0.680851 (90 1660);
PAINT MONO (90 1660);
FORCEPROP 0 LASTPIN (100 1700) $PN DD89
J 2
(90 1710);
DISPLAY 0.680851 (90 1710);
PAINT MONO (90 1710);
FORCEPROP 0 LASTPIN (100 1750) $PN DH89
J 2
(90 1760);
DISPLAY 0.680851 (90 1760);
PAINT MONO (90 1760);
FORCEPROP 0 LASTPIN (100 1800) $PN DM83
J 2
(90 1810);
DISPLAY 0.680851 (90 1810);
PAINT MONO (90 1810);
FORCEPROP 0 LASTPIN (100 1850) $PN DM85
J 2
(90 1860);
DISPLAY 0.680851 (90 1860);
PAINT MONO (90 1860);
FORCEPROP 0 LASTPIN (100 1900) $PN DM89
J 2
(90 1910);
DISPLAY 0.680851 (90 1910);
PAINT MONO (90 1910);
FORCEPROP 0 LASTPIN (100 2050) $PN DN11
J 2
(90 2060);
DISPLAY 0.680851 (90 2060);
PAINT MONO (90 2060);
FORCEPROP 0 LASTPIN (100 2100) $PN DN15
J 2
(90 2110);
DISPLAY 0.680851 (90 2110);
PAINT MONO (90 2110);
FORCEPROP 0 LASTPIN (100 1950) $PN DN3
J 2
(90 1960);
DISPLAY 0.680851 (90 1960);
PAINT MONO (90 1960);
FORCEPROP 0 LASTPIN (100 2000) $PN DN7
J 2
(90 2010);
DISPLAY 0.680851 (90 2010);
PAINT MONO (90 2010);
FORCEPROP 0 LASTPIN (100 2150) $PN DT79
J 2
(90 2160);
DISPLAY 0.680851 (90 2160);
PAINT MONO (90 2160);
FORCEPROP 0 LASTPIN (100 2200) $PN DT85
J 2
(90 2210);
DISPLAY 0.680851 (90 2210);
PAINT MONO (90 2210);
FORCEPROP 0 LASTPIN (100 2250) $PN DT89
J 2
(90 2260);
DISPLAY 0.680851 (90 2260);
PAINT MONO (90 2260);
FORCEPROP 0 LASTPIN (100 2400) $PN DU11
J 2
(90 2410);
DISPLAY 0.680851 (90 2410);
PAINT MONO (90 2410);
FORCEPROP 0 LASTPIN (100 2450) $PN DU15
J 2
(90 2460);
DISPLAY 0.680851 (90 2460);
PAINT MONO (90 2460);
FORCEPROP 0 LASTPIN (100 2300) $PN DU3
J 2
(90 2310);
DISPLAY 0.680851 (90 2310);
PAINT MONO (90 2310);
FORCEPROP 0 LASTPIN (100 2350) $PN DU7
J 2
(90 2360);
DISPLAY 0.680851 (90 2360);
PAINT MONO (90 2360);
FORCEPROP 0 LASTPIN (100 2500) $PN DY85
J 2
(90 2510);
DISPLAY 0.680851 (90 2510);
PAINT MONO (90 2510);
FORCEPROP 0 LASTPIN (100 2550) $PN DY89
J 2
(90 2560);
DISPLAY 0.680851 (90 2560);
PAINT MONO (90 2560);
FORCEPROP 0 LASTPIN (100 2700) $PN EA11
J 2
(90 2710);
DISPLAY 0.680851 (90 2710);
PAINT MONO (90 2710);
FORCEPROP 0 LASTPIN (100 2750) $PN EA15
J 2
(90 2760);
DISPLAY 0.680851 (90 2760);
PAINT MONO (90 2760);
FORCEPROP 0 LASTPIN (100 2600) $PN EA3
J 2
(90 2610);
DISPLAY 0.680851 (90 2610);
PAINT MONO (90 2610);
FORCEPROP 0 LASTPIN (100 2650) $PN EA7
J 2
(90 2660);
DISPLAY 0.680851 (90 2660);
PAINT MONO (90 2660);
FORCEPROP 0 LASTPIN (100 2800) $PN EC78
J 2
(90 2810);
DISPLAY 0.680851 (90 2810);
PAINT MONO (90 2810);
FORCEPROP 0 LASTPIN (100 2850) $PN ED79
J 2
(90 2860);
DISPLAY 0.680851 (90 2860);
PAINT MONO (90 2860);
FORCEPROP 0 LASTPIN (100 2900) $PN ED85
J 2
(90 2910);
DISPLAY 0.680851 (90 2910);
PAINT MONO (90 2910);
FORCEPROP 0 LASTPIN (100 2950) $PN ED89
J 2
(90 2960);
DISPLAY 0.680851 (90 2960);
PAINT MONO (90 2960);
FORCEPROP 0 LASTPIN (100 3050) $PN EE11
J 2
(90 3060);
DISPLAY 0.680851 (90 3060);
PAINT MONO (90 3060);
FORCEPROP 0 LASTPIN (100 3100) $PN EE15
J 2
(90 3110);
DISPLAY 0.680851 (90 3110);
PAINT MONO (90 3110);
FORCEPROP 0 LASTPIN (100 3000) $PN EE7
J 2
(90 3010);
DISPLAY 0.680851 (90 3010);
PAINT MONO (90 3010);
FORCEPROP 0 LASTPIN (100 3150) $PN EE84
J 2
(90 3160);
DISPLAY 0.680851 (90 3160);
PAINT MONO (90 3160);
FORCEPROP 0 LASTPIN (100 3200) $PN EF79
J 2
(90 3210);
DISPLAY 0.680851 (90 3210);
PAINT MONO (90 3210);
FORCEPROP 0 LASTPIN (100 3250) $PN EG80
J 2
(90 3260);
DISPLAY 0.680851 (90 3260);
PAINT MONO (90 3260);
FORCEPROP 0 LASTPIN (100 3300) $PN EJ15
J 2
(90 3310);
DISPLAY 0.680851 (90 3310);
PAINT MONO (90 3310);
FORCEPROP 0 LASTPIN (100 3350) $PN EJ84
J 2
(90 3360);
DISPLAY 0.680851 (90 3360);
PAINT MONO (90 3360);
FORCEPROP 0 LASTPIN (100 3400) $PN EN84
J 2
(90 3410);
DISPLAY 0.680851 (90 3410);
PAINT MONO (90 3410);
FORCEPROP 0 LASTPIN (2500 850) $PN H89
J 0
(2510 860);
DISPLAY 0.680851 (2510 860);
PAINT MONO (2510 860);
FORCEPROP 0 LASTPIN (2500 950) $PN J11
J 0
(2510 960);
DISPLAY 0.680851 (2510 960);
PAINT MONO (2510 960);
FORCEPROP 0 LASTPIN (2500 900) $PN J7
J 0
(2510 910);
DISPLAY 0.680851 (2510 910);
PAINT MONO (2510 910);
FORCEPROP 0 LASTPIN (2500 1000) $PN J80
J 0
(2510 1010);
DISPLAY 0.680851 (2510 1010);
PAINT MONO (2510 1010);
FORCEPROP 0 LASTPIN (2500 1050) $PN K87
J 0
(2510 1060);
DISPLAY 0.680851 (2510 1060);
PAINT MONO (2510 1060);
FORCEPROP 0 LASTPIN (2500 1100) $PN L84
J 0
(2510 1110);
DISPLAY 0.680851 (2510 1110);
PAINT MONO (2510 1110);
FORCEPROP 0 LASTPIN (2500 1150) $PN M85
J 0
(2510 1160);
DISPLAY 0.680851 (2510 1160);
PAINT MONO (2510 1160);
FORCEPROP 0 LASTPIN (2500 1200) $PN M89
J 0
(2510 1210);
DISPLAY 0.680851 (2510 1210);
PAINT MONO (2510 1210);
FORCEPROP 0 LASTPIN (2500 1300) $PN N11
J 0
(2510 1310);
DISPLAY 0.680851 (2510 1310);
PAINT MONO (2510 1310);
FORCEPROP 0 LASTPIN (2500 1250) $PN N7
J 0
(2510 1260);
DISPLAY 0.680851 (2510 1260);
PAINT MONO (2510 1260);
FORCEPROP 0 LASTPIN (2500 1350) $PN P79
J 0
(2510 1360);
DISPLAY 0.680851 (2510 1360);
PAINT MONO (2510 1360);
FORCEPROP 0 LASTPIN (2500 1400) $PN R80
J 0
(2510 1410);
DISPLAY 0.680851 (2510 1410);
PAINT MONO (2510 1410);
FORCEPROP 0 LASTPIN (2500 1450) $PN T85
J 0
(2510 1460);
DISPLAY 0.680851 (2510 1460);
PAINT MONO (2510 1460);
FORCEPROP 0 LASTPIN (2500 1500) $PN T89
J 0
(2510 1510);
DISPLAY 0.680851 (2510 1510);
PAINT MONO (2510 1510);
FORCEPROP 0 LASTPIN (2500 1600) $PN U11
J 0
(2510 1610);
DISPLAY 0.680851 (2510 1610);
PAINT MONO (2510 1610);
FORCEPROP 0 LASTPIN (2500 1650) $PN U15
J 0
(2510 1660);
DISPLAY 0.680851 (2510 1660);
PAINT MONO (2510 1660);
FORCEPROP 0 LASTPIN (2500 1550) $PN U7
J 0
(2510 1560);
DISPLAY 0.680851 (2510 1560);
PAINT MONO (2510 1560);
FORCEPROP 0 LASTPIN (2500 1700) $PN W80
J 0
(2510 1710);
DISPLAY 0.680851 (2510 1710);
PAINT MONO (2510 1710);
FORCEPROP 0 LASTPIN (2500 1750) $PN Y79
J 0
(2510 1760);
DISPLAY 0.680851 (2510 1760);
PAINT MONO (2510 1760);
FORCEPROP 0 LASTPIN (2500 1800) $PN Y85
J 0
(2510 1810);
DISPLAY 0.680851 (2510 1810);
PAINT MONO (2510 1810);
FORCEPROP 0 LASTPIN (2500 1850) $PN Y89
J 0
(2510 1860);
DISPLAY 0.680851 (2510 1860);
PAINT MONO (2510 1860);
FORCEPROP 2 LAST CDS_LIB pure_quanta
J 0
(1300 2075);
DISPLAY INVISIBLE (1300 2075);
FORCEPROP 1 LAST NEEDS_NO_SIZE TRUE
J 0
(1300 2075);
DISPLAY 0.723404 (1300 2075);
PAINT GREEN (1300 2075);
DISPLAY INVISIBLE (1300 2075);
FORCEPROP 1 LAST CDS_LMAN_SYM_OUTLINE -1050,1500,1050,-1450
J 0
(1300 2075);
DISPLAY 0.468085 (1300 2075);
PAINT GREEN (1300 2075);
DISPLAY INVISIBLE (1300 2075);
FORCEPROP 0 LAST CDS_LOCATION U1
J 0
(250 3900);
DISPLAY 1.021277 (250 3900);
DISPLAY INVISIBLE (250 3900);
FORCEPROP 0 LAST $SEC 30
J 0
(250 3900);
DISPLAY 0.680851 (250 3900);
PAINT MONO (250 3900);
DISPLAY INVISIBLE (250 3900);
FORCEPROP 2 LAST CDS_SEC 30
J 0
(250 3900);
DISPLAY 1.021277 (250 3900);
DISPLAY INVISIBLE (250 3900);
FORCEPROP 1 LAST PATH I1
J 0
(1300 2075);
DISPLAY 0.723404 (1300 2075);
PAINT GREEN (1300 2075);
DISPLAY INVISIBLE (1300 2075);
FORCEADD VCC_CORE..1
(-150 4025);
FORCEPROP 3 LASTPIN (-150 3975) SIG_NAME PVCCFA_EHV_FIVRA_CPU1\g
J 0
(-140 3985);
DISPLAY 0.659574 (-140 3985);
PAINT MONO (-140 3985);
DISPLAY INVISIBLE (-140 3985);
FORCEPROP 1 LAST HDL_POWER PVCCFA_EHV_FIVRA_CPU1
J 1
(-150 4075);
DISPLAY 1.148936 (-150 4075);
PAINT GREEN (-150 4075);
FORCEPROP 2 LAST CDS_LIB logical_power
J 0
(-150 4025);
PAINT MONO (-150 4025);
DISPLAY INVISIBLE (-150 4025);
FORCEPROP 1 LAST PATH I2
J 0
(-100 4050);
DISPLAY 0.872340 (-100 4050);
PAINT AQUA (-100 4050);
DISPLAY INVISIBLE (-100 4050);
FORCEADD VCC_CORE..1
(2750 4025);
FORCEPROP 3 LASTPIN (2750 3975) SIG_NAME PVCCFA_EHV_FIVRA_CPU1\g
J 0
(2760 3985);
DISPLAY 0.659574 (2760 3985);
PAINT MONO (2760 3985);
DISPLAY INVISIBLE (2760 3985);
FORCEPROP 1 LAST HDL_POWER PVCCFA_EHV_FIVRA_CPU1
J 1
(2750 4075);
DISPLAY 1.148936 (2750 4075);
PAINT GREEN (2750 4075);
FORCEPROP 2 LAST CDS_LIB logical_power
J 0
(2750 4025);
PAINT MONO (2750 4025);
DISPLAY INVISIBLE (2750 4025);
FORCEPROP 1 LAST PATH I3
J 0
(2800 4050);
DISPLAY 0.872340 (2800 4050);
PAINT AQUA (2800 4050);
DISPLAY INVISIBLE (2800 4050);
FORCEADD QUANTA_TITLE_BLOCK_C..1
(6025 -1475);
FORCEPROP 0 LAST CDS_CON_LAST_MODIFIED Fri Aug 25 14:00:50 2023
J 0
(4140 -1460);
PAINT MONO (4140 -1460);
DISPLAY INVISIBLE (4140 -1460);
FORCEPROP 2 LAST CUSTOM_TXT_CDS <XR_PAGE_TITLE>
J 0
(-1865 3775);
DISPLAY 0.638298 (-1865 3775);
PAINT PINK (-1865 3775);
DISPLAY INVISIBLE (-1865 3775);
FORCEPROP 2 LAST CUSTOM_TXT_CDS <Q_NUMBER>
J 0
(4622 -1372);
DISPLAY 1.212766 (4622 -1372);
FORCEPROP 2 LAST CUSTOM_TXT_CDS <CON_LAST_MODIFIED>
J 0
(4140 -1460);
DISPLAY 0.978723 (4140 -1460);
FORCEPROP 2 LAST CUSTOM_TXT_CDS <CON_PAGE_NUM> OF <CON_TOTAL_PAGES>
J 0
(5600 -1450);
DISPLAY 0.978723 (5600 -1450);
FORCEPROP 2 LAST CUSTOM_TXT_CDS <Q_REV>
J 0
(5841 -1372);
DISPLAY 1.212766 (5841 -1372);
FORCEPROP 2 LAST CUSTOM_TXT_CDS <Q_PROJ>
J 0
(3643 -1373);
DISPLAY 1.212766 (3643 -1373);
FORCEPROP 1 LAST CUSTOM_TXT_CDS <NAME_2>
J 0
(2850 -1425);
FORCEPROP 1 LAST CUSTOM_TXT_CDS <NAME_1>
J 0
(2850 -1300);
FORCEPROP 1 LAST Q_TITLE SPR CPU1 POWER - VCCFA EHV FIVRA (26)
J 0
(-3341 -1449);
DISPLAY 1.957447 (-3341 -1449);
PAINT GREEN (-3341 -1449);
FORCEPROP 1 LAST Q_DEPT 
J 1
(2262 -1426);
DISPLAY 1.957447 (2262 -1426);
PAINT GREEN (2262 -1426);
FORCEPROP 1 LAST COMMENT_BODY TRUE
J 0
(6037 -1488);
DISPLAY 0.978723 (6037 -1488);
PAINT GREEN (6037 -1488);
DISPLAY INVISIBLE (6037 -1488);
FORCEPROP 2 LAST CDS_XR_PAGE_TITLE CR-69 : @S9S_MB_2U_LIB.S9S_MB_2U(SCH_1):PAGE69
J 0
(-1865 3775);
DISPLAY 0.638298 (-1865 3775);
PAINT PINK (-1865 3775);
DISPLAY INVISIBLE (-1865 3775);
FORCEPROP 2 LAST PAGE_BORDER TRUE
J 0
(-1865 3775);
DISPLAY 0.638298 (-1865 3775);
PAINT PINK (-1865 3775);
DISPLAY INVISIBLE (-1865 3775);
FORCEPROP 1 LAST CDS_LMAN_SYM_OUTLINE -9475,6775,100,-125
J 0
(6025 -1475);
DISPLAY 0.468085 (6025 -1475);
PAINT GREEN (6025 -1475);
DISPLAY INVISIBLE (6025 -1475);
FORCEPROP 2 LAST CDS_LIB pure_quanta
J 0
(6025 -1475);
PAINT MONO (6025 -1475);
DISPLAY INVISIBLE (6025 -1475);
WIRE 16 -1 (2750 3975)(2750 3400);
WIRE 16 -1 (-150 3975)(-150 3400);
WIRE 16 -1 (100 3400)(-150 3400);
WIRE 16 -1 (-150 3400)(-150 3350);
WIRE 16 -1 (100 3350)(-150 3350);
WIRE 16 -1 (-150 3350)(-150 3300);
WIRE 16 -1 (100 3300)(-150 3300);
WIRE 16 -1 (-150 3300)(-150 3250);
WIRE 16 -1 (100 3250)(-150 3250);
WIRE 16 -1 (-150 3250)(-150 3200);
WIRE 16 -1 (100 3200)(-150 3200);
WIRE 16 -1 (-150 3200)(-150 3150);
WIRE 16 -1 (100 3150)(-150 3150);
WIRE 16 -1 (-150 3150)(-150 3100);
WIRE 16 -1 (100 3100)(-150 3100);
WIRE 16 -1 (-150 3100)(-150 3050);
WIRE 16 -1 (100 3050)(-150 3050);
WIRE 16 -1 (-150 3050)(-150 3000);
WIRE 16 -1 (-150 3000)(100 3000);
WIRE 16 -1 (-150 3000)(-150 2950);
WIRE 16 -1 (-150 2950)(100 2950);
WIRE 16 -1 (-150 2950)(-150 2900);
WIRE 16 -1 (100 2900)(-150 2900);
WIRE 16 -1 (-150 2900)(-150 2850);
WIRE 16 -1 (-150 2850)(100 2850);
WIRE 16 -1 (-150 2850)(-150 2800);
WIRE 16 -1 (-150 2800)(100 2800);
WIRE 16 -1 (-150 2800)(-150 2750);
WIRE 16 -1 (100 2750)(-150 2750);
WIRE 16 -1 (-150 2750)(-150 2700);
WIRE 16 -1 (-150 2700)(100 2700);
WIRE 16 -1 (-150 2700)(-150 2650);
WIRE 16 -1 (-150 2650)(100 2650);
WIRE 16 -1 (-150 2650)(-150 2600);
WIRE 16 -1 (-150 2600)(100 2600);
WIRE 16 -1 (-150 2600)(-150 2550);
WIRE 16 -1 (-150 2550)(100 2550);
WIRE 16 -1 (-150 2550)(-150 2500);
WIRE 16 -1 (-150 2500)(100 2500);
WIRE 16 -1 (-150 2500)(-150 2450);
WIRE 16 -1 (-150 2450)(100 2450);
WIRE 16 -1 (-150 2450)(-150 2400);
WIRE 16 -1 (-150 2400)(100 2400);
WIRE 16 -1 (-150 2400)(-150 2350);
WIRE 16 -1 (-150 2350)(100 2350);
WIRE 16 -1 (-150 2350)(-150 2300);
WIRE 16 -1 (-150 2300)(100 2300);
WIRE 16 -1 (-150 2300)(-150 2250);
WIRE 16 -1 (-150 2250)(100 2250);
WIRE 16 -1 (-150 2250)(-150 2200);
WIRE 16 -1 (-150 2200)(100 2200);
WIRE 16 -1 (-150 2200)(-150 2150);
WIRE 16 -1 (-150 2150)(100 2150);
WIRE 16 -1 (-150 2150)(-150 2100);
WIRE 16 -1 (-150 2100)(100 2100);
WIRE 16 -1 (-150 2100)(-150 2050);
WIRE 16 -1 (-150 2050)(100 2050);
WIRE 16 -1 (-150 2050)(-150 2000);
WIRE 16 -1 (-150 2000)(100 2000);
WIRE 16 -1 (-150 2000)(-150 1950);
WIRE 16 -1 (-150 1950)(100 1950);
WIRE 16 -1 (-150 1950)(-150 1900);
WIRE 16 -1 (-150 1900)(100 1900);
WIRE 16 -1 (-150 1900)(-150 1850);
WIRE 16 -1 (-150 1850)(100 1850);
WIRE 16 -1 (-150 1850)(-150 1800);
WIRE 16 -1 (-150 1800)(100 1800);
WIRE 16 -1 (-150 1800)(-150 1750);
WIRE 16 -1 (-150 1750)(100 1750);
WIRE 16 -1 (-150 1750)(-150 1700);
WIRE 16 -1 (100 1700)(-150 1700);
WIRE 16 -1 (-150 1700)(-150 1650);
WIRE 16 -1 (-150 1650)(100 1650);
WIRE 16 -1 (-150 1650)(-150 1600);
WIRE 16 -1 (-150 1600)(100 1600);
WIRE 16 -1 (-150 1600)(-150 1550);
WIRE 16 -1 (-150 1550)(100 1550);
WIRE 16 -1 (-150 1550)(-150 1500);
WIRE 16 -1 (-150 1500)(100 1500);
WIRE 16 -1 (-150 1500)(-150 1450);
WIRE 16 -1 (-150 1450)(100 1450);
WIRE 16 -1 (-150 1450)(-150 1400);
WIRE 16 -1 (-150 1400)(100 1400);
WIRE 16 -1 (-150 1400)(-150 1350);
WIRE 16 -1 (-150 1350)(100 1350);
WIRE 16 -1 (-150 1350)(-150 1300);
WIRE 16 -1 (-150 1300)(100 1300);
WIRE 16 -1 (-150 1300)(-150 1250);
WIRE 16 -1 (-150 1250)(100 1250);
WIRE 16 -1 (-150 1250)(-150 1200);
WIRE 16 -1 (-150 1200)(100 1200);
WIRE 16 -1 (-150 1200)(-150 1150);
WIRE 16 -1 (-150 1150)(100 1150);
WIRE 16 -1 (-150 1150)(-150 1100);
WIRE 16 -1 (-150 1100)(100 1100);
WIRE 16 -1 (-150 1100)(-150 1050);
WIRE 16 -1 (-150 1050)(100 1050);
WIRE 16 -1 (-150 1050)(-150 1000);
WIRE 16 -1 (100 1000)(-150 1000);
WIRE 16 -1 (-150 1000)(-150 950);
WIRE 16 -1 (-150 950)(100 950);
WIRE 16 -1 (-150 950)(-150 900);
WIRE 16 -1 (-150 900)(100 900);
WIRE 16 -1 (2750 750)(2500 750);
WIRE 16 -1 (2750 800)(2500 800);
WIRE 16 -1 (2750 800)(2750 750);
WIRE 16 -1 (2750 850)(2500 850);
WIRE 16 -1 (2750 850)(2750 800);
WIRE 16 -1 (2500 900)(2750 900);
WIRE 16 -1 (2750 850)(2750 900);
WIRE 16 -1 (2750 950)(2500 950);
WIRE 16 -1 (2750 900)(2750 950);
WIRE 16 -1 (2750 1000)(2500 1000);
WIRE 16 -1 (2750 1000)(2750 950);
WIRE 16 -1 (2750 1050)(2750 1000);
WIRE 16 -1 (2750 1050)(2500 1050);
WIRE 16 -1 (2750 1100)(2500 1100);
WIRE 16 -1 (2750 1100)(2750 1050);
WIRE 16 -1 (2500 1150)(2750 1150);
WIRE 16 -1 (2750 1150)(2750 1100);
WIRE 16 -1 (2500 1200)(2750 1200);
WIRE 16 -1 (2750 1200)(2750 1150);
WIRE 16 -1 (2500 1250)(2750 1250);
WIRE 16 -1 (2750 1200)(2750 1250);
WIRE 16 -1 (2500 1300)(2750 1300);
WIRE 16 -1 (2750 1300)(2750 1250);
WIRE 16 -1 (2500 1350)(2750 1350);
WIRE 16 -1 (2750 1350)(2750 1300);
WIRE 16 -1 (2500 1400)(2750 1400);
WIRE 16 -1 (2750 1400)(2750 1350);
WIRE 16 -1 (2500 1450)(2750 1450);
WIRE 16 -1 (2750 1450)(2750 1400);
WIRE 16 -1 (2500 1500)(2750 1500);
WIRE 16 -1 (2750 1500)(2750 1450);
WIRE 16 -1 (2500 1550)(2750 1550);
WIRE 16 -1 (2750 1550)(2750 1500);
WIRE 16 -1 (2750 1600)(2500 1600);
WIRE 16 -1 (2750 1600)(2750 1550);
WIRE 16 -1 (2750 1650)(2500 1650);
WIRE 16 -1 (2750 1650)(2750 1600);
WIRE 16 -1 (2750 1700)(2500 1700);
WIRE 16 -1 (2750 1700)(2750 1650);
WIRE 16 -1 (2750 1750)(2500 1750);
WIRE 16 -1 (2750 1750)(2750 1700);
WIRE 16 -1 (2750 1800)(2500 1800);
WIRE 16 -1 (2750 1800)(2750 1750);
WIRE 16 -1 (2750 1850)(2500 1850);
WIRE 16 -1 (2750 1850)(2750 1800);
WIRE 16 -1 (2750 1900)(2500 1900);
WIRE 16 -1 (2750 1900)(2750 1850);
WIRE 16 -1 (2750 1950)(2500 1950);
WIRE 16 -1 (2750 1950)(2750 1900);
WIRE 16 -1 (2750 2000)(2500 2000);
WIRE 16 -1 (2750 2000)(2750 1950);
WIRE 16 -1 (2750 2000)(2750 2050);
WIRE 16 -1 (2500 2050)(2750 2050);
WIRE 16 -1 (2750 2100)(2500 2100);
WIRE 16 -1 (2750 2050)(2750 2100);
WIRE 16 -1 (2750 2150)(2500 2150);
WIRE 16 -1 (2750 2150)(2750 2100);
WIRE 16 -1 (2750 2200)(2500 2200);
WIRE 16 -1 (2750 2200)(2750 2150);
WIRE 16 -1 (2750 2250)(2500 2250);
WIRE 16 -1 (2750 2250)(2750 2200);
WIRE 16 -1 (2500 2300)(2750 2300);
WIRE 16 -1 (2750 2300)(2750 2250);
WIRE 16 -1 (2500 2350)(2750 2350);
WIRE 16 -1 (2750 2350)(2750 2300);
WIRE 16 -1 (2500 2400)(2750 2400);
WIRE 16 -1 (2750 2350)(2750 2400);
WIRE 16 -1 (2500 2450)(2750 2450);
WIRE 16 -1 (2750 2450)(2750 2400);
WIRE 16 -1 (2500 2500)(2750 2500);
WIRE 16 -1 (2750 2500)(2750 2450);
WIRE 16 -1 (2500 2550)(2750 2550);
WIRE 16 -1 (2750 2550)(2750 2500);
WIRE 16 -1 (2500 2600)(2750 2600);
WIRE 16 -1 (2750 2600)(2750 2550);
WIRE 16 -1 (2500 2650)(2750 2650);
WIRE 16 -1 (2750 2650)(2750 2600);
WIRE 16 -1 (2500 2700)(2750 2700);
WIRE 16 -1 (2750 2700)(2750 2650);
WIRE 16 -1 (2750 2750)(2500 2750);
WIRE 16 -1 (2750 2750)(2750 2700);
WIRE 16 -1 (2750 2800)(2500 2800);
WIRE 16 -1 (2750 2800)(2750 2750);
WIRE 16 -1 (2750 2850)(2500 2850);
WIRE 16 -1 (2750 2850)(2750 2800);
WIRE 16 -1 (2750 2900)(2500 2900);
WIRE 16 -1 (2750 2900)(2750 2850);
WIRE 16 -1 (2750 2950)(2500 2950);
WIRE 16 -1 (2750 2950)(2750 2900);
WIRE 16 -1 (2750 3000)(2500 3000);
WIRE 16 -1 (2750 3000)(2750 2950);
WIRE 16 -1 (2750 3050)(2500 3050);
WIRE 16 -1 (2750 3050)(2750 3000);
WIRE 16 -1 (2750 3100)(2750 3050);
WIRE 16 -1 (2750 3100)(2500 3100);
WIRE 16 -1 (2750 3150)(2500 3150);
WIRE 16 -1 (2750 3150)(2750 3100);
WIRE 16 -1 (2500 3200)(2750 3200);
WIRE 16 -1 (2750 3150)(2750 3200);
WIRE 16 -1 (2750 3250)(2500 3250);
WIRE 16 -1 (2750 3200)(2750 3250);
WIRE 16 -1 (2750 3300)(2500 3300);
WIRE 16 -1 (2750 3300)(2750 3250);
WIRE 16 -1 (2750 3350)(2500 3350);
WIRE 16 -1 (2750 3350)(2750 3300);
WIRE 16 -1 (2750 3400)(2500 3400);
WIRE 16 -1 (2750 3400)(2750 3350);
DOT 1 (-150 1900);
DOT 1 (-150 2250);
DOT 1 (-150 2200);
DOT 1 (2750 2300);
DOT 1 (2750 3350);
DOT 1 (2750 3400);
DOT 1 (2750 3250);
DOT 1 (2750 3300);
DOT 1 (2750 3200);
DOT 1 (2750 3150);
DOT 1 (2750 3100);
DOT 1 (2750 3000);
DOT 1 (2750 3050);
DOT 1 (2750 2950);
DOT 1 (2750 2850);
DOT 1 (2750 2900);
DOT 1 (2750 2750);
DOT 1 (2750 2800);
DOT 1 (2750 2700);
DOT 1 (2750 2650);
DOT 1 (2750 2600);
DOT 1 (2750 2450);
DOT 1 (2750 2500);
DOT 1 (2750 2550);
DOT 1 (2750 2400);
DOT 1 (2750 2350);
DOT 1 (2750 2200);
DOT 1 (2750 2250);
DOT 1 (2750 2100);
DOT 1 (2750 2150);
DOT 1 (2750 2050);
DOT 1 (2750 1950);
DOT 1 (2750 2000);
DOT 1 (2750 1850);
DOT 1 (2750 1900);
DOT 1 (2750 1800);
DOT 1 (2750 1750);
DOT 1 (2750 1700);
DOT 1 (2750 1650);
DOT 1 (2750 1600);
DOT 1 (2750 1550);
DOT 1 (2750 1500);
DOT 1 (2750 1450);
DOT 1 (2750 1300);
DOT 1 (2750 1400);
DOT 1 (2750 1350);
DOT 1 (2750 1200);
DOT 1 (2750 1250);
DOT 1 (2750 1050);
DOT 1 (2750 1150);
DOT 1 (2750 1100);
DOT 1 (2750 950);
DOT 1 (2750 1000);
DOT 1 (2750 900);
DOT 1 (2750 800);
DOT 1 (2750 850);
DOT 1 (-150 3350);
DOT 1 (-150 3400);
DOT 1 (-150 3300);
DOT 1 (-150 3250);
DOT 1 (-150 3100);
DOT 1 (-150 3150);
DOT 1 (-150 3200);
DOT 1 (-150 3050);
DOT 1 (-150 3000);
DOT 1 (-150 2950);
DOT 1 (-150 2850);
DOT 1 (-150 2900);
DOT 1 (-150 2800);
DOT 1 (-150 2750);
DOT 1 (-150 2700);
DOT 1 (-150 2600);
DOT 1 (-150 2650);
DOT 1 (-150 2550);
DOT 1 (-150 2500);
DOT 1 (-150 2450);
DOT 1 (-150 2400);
DOT 1 (-150 2350);
DOT 1 (-150 2300);
DOT 1 (-150 2150);
DOT 1 (-150 2100);
DOT 1 (-150 2050);
DOT 1 (-150 1950);
DOT 1 (-150 2000);
DOT 1 (-150 1850);
DOT 1 (-150 1800);
DOT 1 (-150 1700);
DOT 1 (-150 1750);
DOT 1 (-150 1650);
DOT 1 (-150 1550);
DOT 1 (-150 1600);
DOT 1 (-150 1500);
DOT 1 (-150 1450);
DOT 1 (-150 1400);
DOT 1 (-150 1350);
DOT 1 (-150 1300);
DOT 1 (-150 1200);
DOT 1 (-150 1250);
DOT 1 (-150 1150);
DOT 1 (-150 1100);
DOT 1 (-150 1050);
DOT 1 (-150 1000);
DOT 1 (-150 950);
QUIT
